# SCM (Grand Teton) — schematic netlist excerpt (pin names and nets, part order shuffled) for the footprints in the layout excerpt that follows; sources: Cadence DE-HDL packaged netlist, KiCad conversion of 12092022_DA0F0TMDCD0_F0T_Management_Board_D_brd_V3_OCP.brd

R883  Q_RES  8.2K 5% EMPTY  pkg 0402LF  page 50 : A = P3V3_AUX ; B = REAR_AC_PWR_BMC_BTN_N
C47  Q_CAP  1UF 25V 10% X6S  pkg C0402  page 17 : A = P1V0_STBY_RC_VCC10A ; B = GND

(kicad_pcb
	(version 20260206)
	(generator "pcbnew")
	(generator_version "10.0")
	(general
		(thickness 1.6)
		(legacy_teardrops no)
	)
	(paper "A4")
	(title_block
		(title "12092022_DA0F0TMDCD0_F0T_Management_Board_D_brd_V3_OCP.brd")
		(comment 1 "Grand Teton / footprints 1229-1230 of 1440")
	)
	(layers
		(0 "F.Cu" signal "TOP")
		(4 "In1.Cu" signal "GND")
		(6 "In2.Cu" signal "IN1")
		(8 "In3.Cu" signal "GND1")
		(10 "In4.Cu" signal "IN2")
		(12 "In5.Cu" signal "VCC")
		(14 "In6.Cu" signal "VCC1")
		(16 "In7.Cu" signal "IN3")
		(18 "In8.Cu" signal "GND2")
		(20 "In9.Cu" signal "IN4")
		(22 "In10.Cu" signal "GND3")
		(2 "B.Cu" signal "BOTTOM")
		(9 "F.Adhes" user "F.Adhesive")
		(11 "B.Adhes" user "B.Adhesive")
		(13 "F.Paste" user "Package Geometry/Pastemask Top")
		(15 "B.Paste" user "Package Geometry/Pastemask Bottom")
		(5 "F.SilkS" user "Ref Des/Silkscreen Top")
		(7 "B.SilkS" user "Ref Des/Silkscreen Bottom")
		(1 "F.Mask" user "Board Geometry/Soldermask Top")
		(3 "B.Mask" user "Board Geometry/Soldermask Bottom")
		(17 "Dwgs.User" user "User.Drawings")
		(19 "Cmts.User" user "User.Comments")
		(21 "Eco1.User" user "User.Eco1")
		(23 "Eco2.User" user "User.Eco2")
		(25 "Edge.Cuts" user "Board Geometry/Outline")
		(27 "Margin" user)
		(31 "F.CrtYd" user "Package Geometry/Place Bound Top")
		(29 "B.CrtYd" user "Package Geometry/Place Bound Bottom")
		(35 "F.Fab" user "Ref Des/Assembly Top")
		(33 "B.Fab" user "Ref Des/Assembly Bottom")
	)
	(footprint ""
		(layer "B.Cu")
		(at 68.58 -14.478)
		(property "Reference" "R883"
			(at 0 0 0)
			(layer "B.SilkS")
			(hide yes)
			(effects
				(font
					(size 1.27 1.27)
				)
				(justify mirror)
			)
		)
		(property "Value" ""
			(at 0 0 0)
			(layer "B.Fab")
			(effects
				(font
					(size 1.27 1.27)
				)
				(justify mirror)
			)
		)
		(duplicate_pad_numbers_are_jumpers no)
		(fp_line
			(start -0.7874 -0.4064)
			(end -0.7874 0.4064)
			(stroke
				(width 0.1524)
				(type default)
			)
			(layer "B.SilkS")
		)
		(fp_line
			(start -0.7874 0.4064)
			(end 0.7874 0.4064)
			(stroke
				(width 0.1524)
				(type default)
			)
			(layer "B.SilkS")
		)
		(fp_line
			(start 0.7874 -0.4064)
			(end -0.7874 -0.4064)
			(stroke
				(width 0.1524)
				(type default)
			)
			(layer "B.SilkS")
		)
		(fp_line
			(start 0.7874 0.4064)
			(end 0.7874 -0.4064)
			(stroke
				(width 0.1524)
				(type default)
			)
			(layer "B.SilkS")
		)
		(fp_line
			(start -0.67945 -0.3048)
			(end -0.67945 0.3048)
			(stroke
				(width 0.1)
				(type default)
			)
			(layer "B.Fab")
		)
		(fp_line
			(start -0.67945 0.3048)
			(end -0.120396 0.3048)
			(stroke
				(width 0.1)
				(type default)
			)
			(layer "B.Fab")
		)
		(fp_line
			(start -0.12065 -0.3048)
			(end -0.67945 -0.3048)
			(stroke
				(width 0.1)
				(type default)
			)
			(layer "B.Fab")
		)
		(fp_line
			(start -0.12065 -0.2794)
			(end -0.12065 -0.3048)
			(stroke
				(width 0.1)
				(type default)
			)
			(layer "B.Fab")
		)
		(fp_line
			(start -0.120396 0.2794)
			(end 0.12065 0.2794)
			(stroke
				(width 0.1)
				(type default)
			)
			(layer "B.Fab")
		)
		(fp_line
			(start -0.120396 0.3048)
			(end -0.120396 0.2794)
			(stroke
				(width 0.1)
				(type default)
			)
			(layer "B.Fab")
		)
		(fp_line
			(start 0.12065 -0.305054)
			(end 0.12065 -0.2794)
			(stroke
				(width 0.1)
				(type default)
			)
			(layer "B.Fab")
		)
		(fp_line
			(start 0.12065 -0.2794)
			(end -0.12065 -0.2794)
			(stroke
				(width 0.1)
				(type default)
			)
			(layer "B.Fab")
		)
		(fp_line
			(start 0.12065 0.2794)
			(end 0.12065 0.3048)
			(stroke
				(width 0.1)
				(type default)
			)
			(layer "B.Fab")
		)
		(fp_line
			(start 0.12065 0.3048)
			(end 0.67945 0.3048)
			(stroke
				(width 0.1)
				(type default)
			)
			(layer "B.Fab")
		)
		(fp_line
			(start 0.67945 -0.305054)
			(end 0.12065 -0.305054)
			(stroke
				(width 0.1)
				(type default)
			)
			(layer "B.Fab")
		)
		(fp_line
			(start 0.67945 0.3048)
			(end 0.67945 -0.305054)
			(stroke
				(width 0.1)
				(type default)
			)
			(layer "B.Fab")
		)
		(pad "1" smd circle
			(at 0.40005 0 180)
			(size 0 0)
			(layers "B.Cu" "B.Mask" "B.Paste")
			(net "P3V3_AUX")
		)
		(pad "2" smd circle
			(at -0.40005 0 180)
			(size 0 0)
			(layers "B.Cu" "B.Mask" "B.Paste")
			(net "REAR_AC_PWR_BMC_BTN_N")
		)
	)
	(footprint ""
		(layer "B.Cu")
		(at 68.95338 -55.353966 90)
		(property "Reference" "C47"
			(at 0 0 90)
			(layer "B.SilkS")
			(hide yes)
			(effects
				(font
					(size 1.27 1.27)
				)
				(justify mirror)
			)
		)
		(property "Value" ""
			(at 0 0 90)
			(layer "B.Fab")
			(effects
				(font
					(size 1.27 1.27)
				)
				(justify mirror)
			)
		)
		(duplicate_pad_numbers_are_jumpers no)
		(fp_line
			(start 0.7874 -0.4064)
			(end -0.7874 -0.4064)
			(stroke
				(width 0.1524)
				(type default)
			)
			(layer "B.SilkS")
		)
		(fp_line
			(start -0.7874 -0.4064)
			(end -0.7874 0.4064)
			(stroke
				(width 0.1524)
				(type default)
			)
			(layer "B.SilkS")
		)
		(fp_line
			(start 0.7874 0.4064)
			(end 0.7874 -0.4064)
			(stroke
				(width 0.1524)
				(type default)
			)
			(layer "B.SilkS")
		)
		(fp_line
			(start -0.7874 0.4064)
			(end 0.7874 0.4064)
			(stroke
				(width 0.1524)
				(type default)
			)
			(layer "B.SilkS")
		)
		(fp_line
			(start 0.67945 -0.305054)
			(end 0.12065 -0.305054)
			(stroke
				(width 0.1)
				(type default)
			)
			(layer "B.Fab")
		)
		(fp_line
			(start 0.12065 -0.305054)
			(end 0.12065 -0.2794)
			(stroke
				(width 0.1)
				(type default)
			)
			(layer "B.Fab")
		)
		(fp_line
			(start -0.12065 -0.3048)
			(end -0.67945 -0.3048)
			(stroke
				(width 0.1)
				(type default)
			)
			(layer "B.Fab")
		)
		(fp_line
			(start -0.67945 -0.3048)
			(end -0.67945 0.3048)
			(stroke
				(width 0.1)
				(type default)
			)
			(layer "B.Fab")
		)
		(fp_line
			(start 0.12065 -0.2794)
			(end -0.12065 -0.2794)
			(stroke
				(width 0.1)
				(type default)
			)
			(layer "B.Fab")
		)
		(fp_line
			(start -0.12065 -0.2794)
			(end -0.12065 -0.3048)
			(stroke
				(width 0.1)
				(type default)
			)
			(layer "B.Fab")
		)
		(fp_line
			(start 0.12065 0.2794)
			(end 0.12065 0.3048)
			(stroke
				(width 0.1)
				(type default)
			)
			(layer "B.Fab")
		)
		(fp_line
			(start -0.120396 0.2794)
			(end 0.12065 0.2794)
			(stroke
				(width 0.1)
				(type default)
			)
			(layer "B.Fab")
		)
		(fp_line
			(start 0.67945 0.3048)
			(end 0.67945 -0.305054)
			(stroke
				(width 0.1)
				(type default)
			)
			(layer "B.Fab")
		)
		(fp_line
			(start 0.12065 0.3048)
			(end 0.67945 0.3048)
			(stroke
				(width 0.1)
				(type default)
			)
			(layer "B.Fab")
		)
		(fp_line
			(start -0.120396 0.3048)
			(end -0.120396 0.2794)
			(stroke
				(width 0.1)
				(type default)
			)
			(layer "B.Fab")
		)
		(fp_line
			(start -0.67945 0.3048)
			(end -0.120396 0.3048)
			(stroke
				(width 0.1)
				(type default)
			)
			(layer "B.Fab")
		)
		(pad "1" smd circle
			(at 0.40005 0 270)
			(size 0 0)
			(layers "B.Cu" "B.Mask" "B.Paste")
			(net "P1V0_STBY_RC_VCC10A")
		)
		(pad "2" smd circle
			(at -0.40005 0 270)
			(size 0 0)
			(layers "B.Cu" "B.Mask" "B.Paste")
			(net "GND")
		)
	)
)
